(kicad_pcb
	(version 20260206)
	(generator "pcbnew")
	(generator_version "10.0")
	(general
		(thickness 1.6)
		(legacy_teardrops no)
	)
	(paper "A4")
	(title_block
		(title "03242023_DA0F0TMBIJ0_F0T_Motherboard_J_brd_V01_OCP.brd")
		(comment 1 "Grand Teton / footprints 3432-3438 of 6105")
	)
	(layers
		(0 "F.Cu" signal "TOP")
		(4 "In1.Cu" signal "GND")
		(6 "In2.Cu" signal "IN1")
		(8 "In3.Cu" signal "GND1")
		(10 "In4.Cu" signal "IN2")
		(12 "In5.Cu" signal "GND2")
		(14 "In6.Cu" signal "IN3")
		(16 "In7.Cu" signal "GND3")
		(18 "In8.Cu" signal "VCC")
		(20 "In9.Cu" signal "VCC1")
		(22 "In10.Cu" signal "GND4")
		(24 "In11.Cu" signal "IN4")
		(26 "In12.Cu" signal "GND5")
		(28 "In13.Cu" signal "IN5")
		(30 "In14.Cu" signal "GND6")
		(32 "In15.Cu" signal "IN6")
		(34 "In16.Cu" signal "GND7")
		(2 "B.Cu" signal "BOTTOM")
		(9 "F.Adhes" user "F.Adhesive")
		(11 "B.Adhes" user "B.Adhesive")
		(13 "F.Paste" user "Package Geometry/Pastemask Top")
		(15 "B.Paste" user "Package Geometry/Pastemask Bottom")
		(5 "F.SilkS" user "Ref Des/Silkscreen Top")
		(7 "B.SilkS" user "Ref Des/Silkscreen Bottom")
		(1 "F.Mask" user "Board Geometry/Soldermask Top")
		(3 "B.Mask" user "Board Geometry/Soldermask Bottom")
		(17 "Dwgs.User" user "User.Drawings")
		(19 "Cmts.User" user "User.Comments")
		(21 "Eco1.User" user "User.Eco1")
		(23 "Eco2.User" user "User.Eco2")
		(25 "Edge.Cuts" user "Board Geometry/Outline")
		(27 "Margin" user)
		(31 "F.CrtYd" user "Package Geometry/Place Bound Top")
		(29 "B.CrtYd" user "Package Geometry/Place Bound Bottom")
		(35 "F.Fab" user "Ref Des/Assembly Top")
		(33 "B.Fab" user "Ref Des/Assembly Bottom")
	)
	(footprint ""
		(layer "F.Cu")
		(at 351.97288 -363.692948 -90)
		(property "Reference" "R2372"
			(at 0 0 270)
			(layer "F.SilkS")
			(hide yes)
			(effects
				(font
					(size 1.27 1.27)
				)
			)
		)
		(property "Value" ""
			(at 0 0 270)
			(layer "F.Fab")
			(effects
				(font
					(size 1.27 1.27)
				)
			)
		)
		(duplicate_pad_numbers_are_jumpers no)
		(fp_line
			(start -0.7874 0.4064)
			(end -0.7874 -0.4064)
			(stroke
				(width 0.1524)
				(type default)
			)
			(layer "F.SilkS")
		)
		(fp_line
			(start 0.7874 0.4064)
			(end -0.7874 0.4064)
			(stroke
				(width 0.1524)
				(type default)
			)
			(layer "F.SilkS")
		)
		(fp_line
			(start -0.7874 -0.4064)
			(end 0.7874 -0.4064)
			(stroke
				(width 0.1524)
				(type default)
			)
			(layer "F.SilkS")
		)
		(fp_line
			(start 0.7874 -0.4064)
			(end 0.7874 0.4064)
			(stroke
				(width 0.1524)
				(type default)
			)
			(layer "F.SilkS")
		)
		(fp_line
			(start -0.67945 0.3048)
			(end -0.67945 -0.305054)
			(stroke
				(width 0.1)
				(type default)
			)
			(layer "F.Fab")
		)
		(fp_line
			(start -0.12065 0.3048)
			(end -0.67945 0.3048)
			(stroke
				(width 0.1)
				(type default)
			)
			(layer "F.Fab")
		)
		(fp_line
			(start 0.120396 0.3048)
			(end 0.120396 0.2794)
			(stroke
				(width 0.1)
				(type default)
			)
			(layer "F.Fab")
		)
		(fp_line
			(start 0.67945 0.3048)
			(end 0.120396 0.3048)
			(stroke
				(width 0.1)
				(type default)
			)
			(layer "F.Fab")
		)
		(fp_line
			(start -0.12065 0.2794)
			(end -0.12065 0.3048)
			(stroke
				(width 0.1)
				(type default)
			)
			(layer "F.Fab")
		)
		(fp_line
			(start 0.120396 0.2794)
			(end -0.12065 0.2794)
			(stroke
				(width 0.1)
				(type default)
			)
			(layer "F.Fab")
		)
		(fp_line
			(start -0.12065 -0.2794)
			(end 0.12065 -0.2794)
			(stroke
				(width 0.1)
				(type default)
			)
			(layer "F.Fab")
		)
		(fp_line
			(start 0.12065 -0.2794)
			(end 0.12065 -0.3048)
			(stroke
				(width 0.1)
				(type default)
			)
			(layer "F.Fab")
		)
		(fp_line
			(start 0.12065 -0.3048)
			(end 0.67945 -0.3048)
			(stroke
				(width 0.1)
				(type default)
			)
			(layer "F.Fab")
		)
		(fp_line
			(start 0.67945 -0.3048)
			(end 0.67945 0.3048)
			(stroke
				(width 0.1)
				(type default)
			)
			(layer "F.Fab")
		)
		(fp_line
			(start -0.67945 -0.305054)
			(end -0.12065 -0.305054)
			(stroke
				(width 0.1)
				(type default)
			)
			(layer "F.Fab")
		)
		(fp_line
			(start -0.12065 -0.305054)
			(end -0.12065 -0.2794)
			(stroke
				(width 0.1)
				(type default)
			)
			(layer "F.Fab")
		)
		(pad "1" smd circle
			(at -0.40005 0 270)
			(size 0 0)
			(layers "F.Cu" "F.Mask" "F.Paste")
			(net "SMB_VR_3V3AUX_SDA_R3")
		)
		(pad "2" smd circle
			(at 0.40005 0 270)
			(size 0 0)
			(layers "F.Cu" "F.Mask" "F.Paste")
			(net "SMB_DIO_PVCCIN_CPU0")
		)
	)
	(footprint ""
		(layer "F.Cu")
		(at 22.991572 -162.20567 -90)
		(property "Reference" "PC389"
			(at 0 0 270)
			(layer "F.SilkS")
			(hide yes)
			(effects
				(font
					(size 1.27 1.27)
				)
			)
		)
		(property "Value" ""
			(at 0 0 270)
			(layer "F.Fab")
			(effects
				(font
					(size 1.27 1.27)
				)
			)
		)
		(duplicate_pad_numbers_are_jumpers no)
		(fp_line
			(start -0.7874 0.4064)
			(end -0.7874 -0.4064)
			(stroke
				(width 0.1524)
				(type default)
			)
			(layer "F.SilkS")
		)
		(fp_line
			(start 0.7874 0.4064)
			(end -0.7874 0.4064)
			(stroke
				(width 0.1524)
				(type default)
			)
			(layer "F.SilkS")
		)
		(fp_line
			(start -0.7874 -0.4064)
			(end 0.7874 -0.4064)
			(stroke
				(width 0.1524)
				(type default)
			)
			(layer "F.SilkS")
		)
		(fp_line
			(start 0.7874 -0.4064)
			(end 0.7874 0.4064)
			(stroke
				(width 0.1524)
				(type default)
			)
			(layer "F.SilkS")
		)
		(fp_line
			(start -0.67945 0.3048)
			(end -0.67945 -0.305054)
			(stroke
				(width 0.1)
				(type default)
			)
			(layer "F.Fab")
		)
		(fp_line
			(start -0.12065 0.3048)
			(end -0.67945 0.3048)
			(stroke
				(width 0.1)
				(type default)
			)
			(layer "F.Fab")
		)
		(fp_line
			(start 0.120396 0.3048)
			(end 0.120396 0.2794)
			(stroke
				(width 0.1)
				(type default)
			)
			(layer "F.Fab")
		)
		(fp_line
			(start 0.67945 0.3048)
			(end 0.120396 0.3048)
			(stroke
				(width 0.1)
				(type default)
			)
			(layer "F.Fab")
		)
		(fp_line
			(start -0.12065 0.2794)
			(end -0.12065 0.3048)
			(stroke
				(width 0.1)
				(type default)
			)
			(layer "F.Fab")
		)
		(fp_line
			(start 0.120396 0.2794)
			(end -0.12065 0.2794)
			(stroke
				(width 0.1)
				(type default)
			)
			(layer "F.Fab")
		)
		(fp_line
			(start -0.12065 -0.2794)
			(end 0.12065 -0.2794)
			(stroke
				(width 0.1)
				(type default)
			)
			(layer "F.Fab")
		)
		(fp_line
			(start 0.12065 -0.2794)
			(end 0.12065 -0.3048)
			(stroke
				(width 0.1)
				(type default)
			)
			(layer "F.Fab")
		)
		(fp_line
			(start 0.12065 -0.3048)
			(end 0.67945 -0.3048)
			(stroke
				(width 0.1)
				(type default)
			)
			(layer "F.Fab")
		)
		(fp_line
			(start 0.67945 -0.3048)
			(end 0.67945 0.3048)
			(stroke
				(width 0.1)
				(type default)
			)
			(layer "F.Fab")
		)
		(fp_line
			(start -0.67945 -0.305054)
			(end -0.12065 -0.305054)
			(stroke
				(width 0.1)
				(type default)
			)
			(layer "F.Fab")
		)
		(fp_line
			(start -0.12065 -0.305054)
			(end -0.12065 -0.2794)
			(stroke
				(width 0.1)
				(type default)
			)
			(layer "F.Fab")
		)
		(pad "1" smd circle
			(at -0.40005 0 270)
			(size 0 0)
			(layers "F.Cu" "F.Mask" "F.Paste")
			(net "SH_PVCCD_HV_CPU1_R")
		)
		(pad "2" smd circle
			(at 0.40005 0 270)
			(size 0 0)
			(layers "F.Cu" "F.Mask" "F.Paste")
			(net "VSENSE_PVCCD_HV_CPU1_DN")
		)
	)
	(footprint ""
		(layer "F.Cu")
		(at 464.799934 -22.29993)
		(property "Reference" "H106"
			(at -6.743954 -4.50088 0)
			(unlocked yes)
			(layer "F.SilkS")
			(effects
				(font
					(size 0.7874 0.5842)
					(thickness 0.1524)
				)
				(justify left)
			)
		)
		(property "Value" ""
			(at 0 0 0)
			(layer "F.Fab")
			(effects
				(font
					(size 1.27 1.27)
				)
			)
		)
		(duplicate_pad_numbers_are_jumpers no)
		(pad "1" thru_hole circle
			(at 0 0)
			(size 10.0076 10.0076)
			(drill 5.6134)
			(layers "*.Cu" "*.Mask")
			(remove_unused_layers no)
			(net "GND")
			(clearance -1.9431)
		)
	)
	(footprint ""
		(layer "F.Cu")
		(at 4.699 -49.113948 180)
		(property "Reference" "R580"
			(at 0 0 180)
			(layer "F.SilkS")
			(hide yes)
			(effects
				(font
					(size 1.27 1.27)
				)
			)
		)
		(property "Value" ""
			(at 0 0 180)
			(layer "F.Fab")
			(effects
				(font
					(size 1.27 1.27)
				)
			)
		)
		(duplicate_pad_numbers_are_jumpers no)
		(fp_line
			(start 0.7874 0.4064)
			(end -0.7874 0.4064)
			(stroke
				(width 0.1524)
				(type default)
			)
			(layer "F.SilkS")
		)
		(fp_line
			(start 0.7874 -0.4064)
			(end 0.7874 0.4064)
			(stroke
				(width 0.1524)
				(type default)
			)
			(layer "F.SilkS")
		)
		(fp_line
			(start -0.7874 0.4064)
			(end -0.7874 -0.4064)
			(stroke
				(width 0.1524)
				(type default)
			)
			(layer "F.SilkS")
		)
		(fp_line
			(start -0.7874 -0.4064)
			(end 0.7874 -0.4064)
			(stroke
				(width 0.1524)
				(type default)
			)
			(layer "F.SilkS")
		)
		(fp_line
			(start 0.67945 0.3048)
			(end 0.120396 0.3048)
			(stroke
				(width 0.1)
				(type default)
			)
			(layer "F.Fab")
		)
		(fp_line
			(start 0.67945 -0.3048)
			(end 0.67945 0.3048)
			(stroke
				(width 0.1)
				(type default)
			)
			(layer "F.Fab")
		)
		(fp_line
			(start 0.12065 -0.2794)
			(end 0.12065 -0.3048)
			(stroke
				(width 0.1)
				(type default)
			)
			(layer "F.Fab")
		)
		(fp_line
			(start 0.12065 -0.3048)
			(end 0.67945 -0.3048)
			(stroke
				(width 0.1)
				(type default)
			)
			(layer "F.Fab")
		)
		(fp_line
			(start 0.120396 0.3048)
			(end 0.120396 0.2794)
			(stroke
				(width 0.1)
				(type default)
			)
			(layer "F.Fab")
		)
		(fp_line
			(start 0.120396 0.2794)
			(end -0.12065 0.2794)
			(stroke
				(width 0.1)
				(type default)
			)
			(layer "F.Fab")
		)
		(fp_line
			(start -0.12065 0.3048)
			(end -0.67945 0.3048)
			(stroke
				(width 0.1)
				(type default)
			)
			(layer "F.Fab")
		)
		(fp_line
			(start -0.12065 0.2794)
			(end -0.12065 0.3048)
			(stroke
				(width 0.1)
				(type default)
			)
			(layer "F.Fab")
		)
		(fp_line
			(start -0.12065 -0.2794)
			(end 0.12065 -0.2794)
			(stroke
				(width 0.1)
				(type default)
			)
			(layer "F.Fab")
		)
		(fp_line
			(start -0.12065 -0.305054)
			(end -0.12065 -0.2794)
			(stroke
				(width 0.1)
				(type default)
			)
			(layer "F.Fab")
		)
		(fp_line
			(start -0.67945 0.3048)
			(end -0.67945 -0.305054)
			(stroke
				(width 0.1)
				(type default)
			)
			(layer "F.Fab")
		)
		(fp_line
			(start -0.67945 -0.305054)
			(end -0.12065 -0.305054)
			(stroke
				(width 0.1)
				(type default)
			)
			(layer "F.Fab")
		)
		(pad "1" smd circle
			(at -0.40005 0 180)
			(size 0 0)
			(layers "F.Cu" "F.Mask" "F.Paste")
			(net "SMB_HOST_3V3AUX_SDA_R5")
		)
		(pad "2" smd circle
			(at 0.40005 0 180)
			(size 0 0)
			(layers "F.Cu" "F.Mask" "F.Paste")
			(net "SMB_HOST_BMC_3V3AUX_SDA")
		)
	)
	(footprint ""
		(layer "F.Cu")
		(at 210.74888 -44.795948)
		(property "Reference" "R3531"
			(at 0 0 0)
			(layer "F.SilkS")
			(hide yes)
			(effects
				(font
					(size 1.27 1.27)
				)
			)
		)
		(property "Value" ""
			(at 0 0 0)
			(layer "F.Fab")
			(effects
				(font
					(size 1.27 1.27)
				)
			)
		)
		(duplicate_pad_numbers_are_jumpers no)
		(fp_line
			(start -0.7874 -0.4064)
			(end 0.7874 -0.4064)
			(stroke
				(width 0.1524)
				(type default)
			)
			(layer "F.SilkS")
		)
		(fp_line
			(start -0.7874 0.4064)
			(end -0.7874 -0.4064)
			(stroke
				(width 0.1524)
				(type default)
			)
			(layer "F.SilkS")
		)
		(fp_line
			(start 0.7874 -0.4064)
			(end 0.7874 0.4064)
			(stroke
				(width 0.1524)
				(type default)
			)
			(layer "F.SilkS")
		)
		(fp_line
			(start 0.7874 0.4064)
			(end -0.7874 0.4064)
			(stroke
				(width 0.1524)
				(type default)
			)
			(layer "F.SilkS")
		)
		(fp_line
			(start -0.67945 -0.305054)
			(end -0.12065 -0.305054)
			(stroke
				(width 0.1)
				(type default)
			)
			(layer "F.Fab")
		)
		(fp_line
			(start -0.67945 0.3048)
			(end -0.67945 -0.305054)
			(stroke
				(width 0.1)
				(type default)
			)
			(layer "F.Fab")
		)
		(fp_line
			(start -0.12065 -0.305054)
			(end -0.12065 -0.2794)
			(stroke
				(width 0.1)
				(type default)
			)
			(layer "F.Fab")
		)
		(fp_line
			(start -0.12065 -0.2794)
			(end 0.12065 -0.2794)
			(stroke
				(width 0.1)
				(type default)
			)
			(layer "F.Fab")
		)
		(fp_line
			(start -0.12065 0.2794)
			(end -0.12065 0.3048)
			(stroke
				(width 0.1)
				(type default)
			)
			(layer "F.Fab")
		)
		(fp_line
			(start -0.12065 0.3048)
			(end -0.67945 0.3048)
			(stroke
				(width 0.1)
				(type default)
			)
			(layer "F.Fab")
		)
		(fp_line
			(start 0.120396 0.2794)
			(end -0.12065 0.2794)
			(stroke
				(width 0.1)
				(type default)
			)
			(layer "F.Fab")
		)
		(fp_line
			(start 0.120396 0.3048)
			(end 0.120396 0.2794)
			(stroke
				(width 0.1)
				(type default)
			)
			(layer "F.Fab")
		)
		(fp_line
			(start 0.12065 -0.3048)
			(end 0.67945 -0.3048)
			(stroke
				(width 0.1)
				(type default)
			)
			(layer "F.Fab")
		)
		(fp_line
			(start 0.12065 -0.2794)
			(end 0.12065 -0.3048)
			(stroke
				(width 0.1)
				(type default)
			)
			(layer "F.Fab")
		)
		(fp_line
			(start 0.67945 -0.3048)
			(end 0.67945 0.3048)
			(stroke
				(width 0.1)
				(type default)
			)
			(layer "F.Fab")
		)
		(fp_line
			(start 0.67945 0.3048)
			(end 0.120396 0.3048)
			(stroke
				(width 0.1)
				(type default)
			)
			(layer "F.Fab")
		)
		(pad "1" smd circle
			(at -0.40005 0)
			(size 0 0)
			(layers "F.Cu" "F.Mask" "F.Paste")
			(net "SMB_PCIE_E1S_ISO_EN")
		)
		(pad "2" smd circle
			(at 0.40005 0)
			(size 0 0)
			(layers "F.Cu" "F.Mask" "F.Paste")
			(net "SMB_PCIE_E1S_ISO_EN_R")
		)
	)
	(footprint ""
		(layer "F.Cu")
		(at 320.190622 -61.864748)
		(property "Reference" "R1475"
			(at 0 0 0)
			(layer "F.SilkS")
			(hide yes)
			(effects
				(font
					(size 1.27 1.27)
				)
			)
		)
		(property "Value" ""
			(at 0 0 0)
			(layer "F.Fab")
			(effects
				(font
					(size 1.27 1.27)
				)
			)
		)
		(duplicate_pad_numbers_are_jumpers no)
		(fp_line
			(start -0.7874 -0.4064)
			(end 0.7874 -0.4064)
			(stroke
				(width 0.1524)
				(type default)
			)
			(layer "F.SilkS")
		)
		(fp_line
			(start -0.7874 0.4064)
			(end -0.7874 -0.4064)
			(stroke
				(width 0.1524)
				(type default)
			)
			(layer "F.SilkS")
		)
		(fp_line
			(start 0.7874 -0.4064)
			(end 0.7874 0.4064)
			(stroke
				(width 0.1524)
				(type default)
			)
			(layer "F.SilkS")
		)
		(fp_line
			(start 0.7874 0.4064)
			(end -0.7874 0.4064)
			(stroke
				(width 0.1524)
				(type default)
			)
			(layer "F.SilkS")
		)
		(fp_line
			(start -0.67945 -0.305054)
			(end -0.12065 -0.305054)
			(stroke
				(width 0.1)
				(type default)
			)
			(layer "F.Fab")
		)
		(fp_line
			(start -0.67945 0.3048)
			(end -0.67945 -0.305054)
			(stroke
				(width 0.1)
				(type default)
			)
			(layer "F.Fab")
		)
		(fp_line
			(start -0.12065 -0.305054)
			(end -0.12065 -0.2794)
			(stroke
				(width 0.1)
				(type default)
			)
			(layer "F.Fab")
		)
		(fp_line
			(start -0.12065 -0.2794)
			(end 0.12065 -0.2794)
			(stroke
				(width 0.1)
				(type default)
			)
			(layer "F.Fab")
		)
		(fp_line
			(start -0.12065 0.2794)
			(end -0.12065 0.3048)
			(stroke
				(width 0.1)
				(type default)
			)
			(layer "F.Fab")
		)
		(fp_line
			(start -0.12065 0.3048)
			(end -0.67945 0.3048)
			(stroke
				(width 0.1)
				(type default)
			)
			(layer "F.Fab")
		)
		(fp_line
			(start 0.120396 0.2794)
			(end -0.12065 0.2794)
			(stroke
				(width 0.1)
				(type default)
			)
			(layer "F.Fab")
		)
		(fp_line
			(start 0.120396 0.3048)
			(end 0.120396 0.2794)
			(stroke
				(width 0.1)
				(type default)
			)
			(layer "F.Fab")
		)
		(fp_line
			(start 0.12065 -0.3048)
			(end 0.67945 -0.3048)
			(stroke
				(width 0.1)
				(type default)
			)
			(layer "F.Fab")
		)
		(fp_line
			(start 0.12065 -0.2794)
			(end 0.12065 -0.3048)
			(stroke
				(width 0.1)
				(type default)
			)
			(layer "F.Fab")
		)
		(fp_line
			(start 0.67945 -0.3048)
			(end 0.67945 0.3048)
			(stroke
				(width 0.1)
				(type default)
			)
			(layer "F.Fab")
		)
		(fp_line
			(start 0.67945 0.3048)
			(end 0.120396 0.3048)
			(stroke
				(width 0.1)
				(type default)
			)
			(layer "F.Fab")
		)
		(pad "1" smd circle
			(at -0.40005 0)
			(size 0 0)
			(layers "F.Cu" "F.Mask" "F.Paste")
			(net "P3V3_AUX")
		)
		(pad "2" smd circle
			(at 0.40005 0)
			(size 0 0)
			(layers "F.Cu" "F.Mask" "F.Paste")
			(net "FM_PCH_RING_OSC_BYPASS_MGPIO_TE")
		)
	)
	(footprint ""
		(layer "F.Cu")
		(at 335.5086 -69.002148 90)
		(property "Reference" "Y7"
			(at 3.099816 -1.5494 0)
			(unlocked yes)
			(layer "F.SilkS")
			(effects
				(font
					(size 0.7874 0.5842)
					(thickness 0.1524)
				)
				(justify left)
			)
		)
		(property "Value" ""
			(at 0 0 90)
			(layer "F.Fab")
			(effects
				(font
					(size 1.27 1.27)
				)
			)
		)
		(duplicate_pad_numbers_are_jumpers no)
		(fp_line
			(start 1.6002 -1.9558)
			(end 1.6002 1.9558)
			(stroke
				(width 0.1524)
				(type default)
			)
			(layer "F.SilkS")
		)
		(fp_line
			(start -1.6002 -1.9558)
			(end 1.6002 -1.9558)
			(stroke
				(width 0.1524)
				(type default)
			)
			(layer "F.SilkS")
		)
		(fp_line
			(start 1.6002 1.9558)
			(end -1.6002 1.9558)
			(stroke
				(width 0.1524)
				(type default)
			)
			(layer "F.SilkS")
		)
		(fp_line
			(start -1.6002 1.9558)
			(end -1.6002 -1.9558)
			(stroke
				(width 0.1524)
				(type default)
			)
			(layer "F.SilkS")
		)
		(fp_poly
			(pts
				(xy -0.820166 -4.432046) (xy -1.302766 -5.524246) (xy -0.235966 -5.524246)
			)
			(stroke
				(width 0)
				(type default)
			)
			(fill yes)
			(layer "F.SilkS")
		)
		(fp_line
			(start 1.299972 -1.649984)
			(end 1.299972 1.649984)
			(stroke
				(width 0.1)
				(type default)
			)
			(layer "F.Fab")
		)
		(fp_line
			(start -1.299972 -1.649984)
			(end 1.299972 -1.649984)
			(stroke
				(width 0.1)
				(type default)
			)
			(layer "F.Fab")
		)
		(fp_line
			(start 1.299972 1.649984)
			(end -1.299972 1.649984)
			(stroke
				(width 0.1)
				(type default)
			)
			(layer "F.Fab")
		)
		(fp_line
			(start -1.299972 1.649984)
			(end -1.299972 -1.649984)
			(stroke
				(width 0.1)
				(type default)
			)
			(layer "F.Fab")
		)
		(fp_poly
			(pts
				(xy -1.7145 -1.0668) (xy -2.8067 -1.651) (xy -2.8067 -0.5842)
			)
			(stroke
				(width 0)
				(type default)
			)
			(fill yes)
			(layer "F.Fab")
		)
		(pad "1" smd rect
			(at -0.849884 -1.100074 90)
			(size 1.2192 1.4224)
			(layers "F.Cu" "F.Mask" "F.Paste")
			(net "XTAL_PCH_25M_IN_R")
		)
		(pad "2" smd rect
			(at -0.849884 1.100074 90)
			(size 1.2192 1.4224)
			(layers "F.Cu" "F.Mask" "F.Paste")
			(net "GND")
		)
		(pad "3" smd rect
			(at 0.849884 1.100074 90)
			(size 1.2192 1.4224)
			(layers "F.Cu" "F.Mask" "F.Paste")
			(net "XTAL_PCH_25M_OUT")
		)
		(pad "4" smd rect
			(at 0.849884 -1.100074 90)
			(size 1.2192 1.4224)
			(layers "F.Cu" "F.Mask" "F.Paste")
			(net "GND")
		)
	)
)
